(kicad_pcb
	(version 20260206)
	(generator "pcbnew")
	(generator_version "10.0")
	(general
		(thickness 1.6)
		(legacy_teardrops no)
	)
	(paper "A4")
	(title_block
		(title "01162023_DA0F0TEBIF0_F0T_Expander_BD_F_brd_V02_OCP.brd")
		(comment 1 "Grand Teton / footprints 2942-2947 of 9728")
	)
	(layers
		(0 "F.Cu" signal "TOP")
		(4 "In1.Cu" signal "GND")
		(6 "In2.Cu" signal "VCC")
		(8 "In3.Cu" signal "VCC1")
		(10 "In4.Cu" signal "GND1")
		(12 "In5.Cu" signal "IN1")
		(14 "In6.Cu" signal "GND2")
		(16 "In7.Cu" signal "IN2")
		(18 "In8.Cu" signal "GND3")
		(20 "In9.Cu" signal "IN3")
		(22 "In10.Cu" signal "GND4")
		(24 "In11.Cu" signal "IN4")
		(26 "In12.Cu" signal "GND5")
		(28 "In13.Cu" signal "IN5")
		(30 "In14.Cu" signal "GND6")
		(32 "In15.Cu" signal "IN6")
		(34 "In16.Cu" signal "GND7")
		(2 "B.Cu" signal "BOTTOM")
		(9 "F.Adhes" user "F.Adhesive")
		(11 "B.Adhes" user "B.Adhesive")
		(13 "F.Paste" user "Package Geometry/Pastemask Top")
		(15 "B.Paste" user "Package Geometry/Pastemask Bottom")
		(5 "F.SilkS" user "Ref Des/Silkscreen Top")
		(7 "B.SilkS" user "Ref Des/Silkscreen Bottom")
		(1 "F.Mask" user "Board Geometry/Soldermask Top")
		(3 "B.Mask" user "Board Geometry/Soldermask Bottom")
		(17 "Dwgs.User" user "User.Drawings")
		(19 "Cmts.User" user "User.Comments")
		(21 "Eco1.User" user "User.Eco1")
		(23 "Eco2.User" user "User.Eco2")
		(25 "Edge.Cuts" user "Board Geometry/Outline")
		(27 "Margin" user)
		(31 "F.CrtYd" user "Package Geometry/Place Bound Top")
		(29 "B.CrtYd" user "Package Geometry/Place Bound Bottom")
		(35 "F.Fab" user "Ref Des/Assembly Top")
		(33 "B.Fab" user "Ref Des/Assembly Bottom")
	)
	(footprint ""
		(layer "F.Cu")
		(at 381.254 -196.342)
		(property "Reference" "R4695"
			(at 0 0 0)
			(layer "F.SilkS")
			(hide yes)
			(effects
				(font
					(size 1.27 1.27)
				)
			)
		)
		(property "Value" ""
			(at 0 0 0)
			(layer "F.Fab")
			(effects
				(font
					(size 1.27 1.27)
				)
			)
		)
		(duplicate_pad_numbers_are_jumpers no)
		(fp_line
			(start -0.7874 -0.4064)
			(end 0.7874 -0.4064)
			(stroke
				(width 0.1524)
				(type default)
			)
			(layer "F.SilkS")
		)
		(fp_line
			(start -0.7874 0.4064)
			(end -0.7874 -0.4064)
			(stroke
				(width 0.1524)
				(type default)
			)
			(layer "F.SilkS")
		)
		(fp_line
			(start 0.7874 -0.4064)
			(end 0.7874 0.4064)
			(stroke
				(width 0.1524)
				(type default)
			)
			(layer "F.SilkS")
		)
		(fp_line
			(start 0.7874 0.4064)
			(end -0.7874 0.4064)
			(stroke
				(width 0.1524)
				(type default)
			)
			(layer "F.SilkS")
		)
		(fp_line
			(start -0.67945 -0.305054)
			(end -0.12065 -0.305054)
			(stroke
				(width 0.1)
				(type default)
			)
			(layer "F.Fab")
		)
		(fp_line
			(start -0.67945 0.3048)
			(end -0.67945 -0.305054)
			(stroke
				(width 0.1)
				(type default)
			)
			(layer "F.Fab")
		)
		(fp_line
			(start -0.12065 -0.305054)
			(end -0.12065 -0.2794)
			(stroke
				(width 0.1)
				(type default)
			)
			(layer "F.Fab")
		)
		(fp_line
			(start -0.12065 -0.2794)
			(end 0.12065 -0.2794)
			(stroke
				(width 0.1)
				(type default)
			)
			(layer "F.Fab")
		)
		(fp_line
			(start -0.12065 0.2794)
			(end -0.12065 0.3048)
			(stroke
				(width 0.1)
				(type default)
			)
			(layer "F.Fab")
		)
		(fp_line
			(start -0.12065 0.3048)
			(end -0.67945 0.3048)
			(stroke
				(width 0.1)
				(type default)
			)
			(layer "F.Fab")
		)
		(fp_line
			(start 0.120396 0.2794)
			(end -0.12065 0.2794)
			(stroke
				(width 0.1)
				(type default)
			)
			(layer "F.Fab")
		)
		(fp_line
			(start 0.120396 0.3048)
			(end 0.120396 0.2794)
			(stroke
				(width 0.1)
				(type default)
			)
			(layer "F.Fab")
		)
		(fp_line
			(start 0.12065 -0.3048)
			(end 0.67945 -0.3048)
			(stroke
				(width 0.1)
				(type default)
			)
			(layer "F.Fab")
		)
		(fp_line
			(start 0.12065 -0.2794)
			(end 0.12065 -0.3048)
			(stroke
				(width 0.1)
				(type default)
			)
			(layer "F.Fab")
		)
		(fp_line
			(start 0.67945 -0.3048)
			(end 0.67945 0.3048)
			(stroke
				(width 0.1)
				(type default)
			)
			(layer "F.Fab")
		)
		(fp_line
			(start 0.67945 0.3048)
			(end 0.120396 0.3048)
			(stroke
				(width 0.1)
				(type default)
			)
			(layer "F.Fab")
		)
		(pad "1" smd circle
			(at -0.40005 0)
			(size 0 0)
			(layers "F.Cu" "F.Mask" "F.Paste")
			(net "NIC2_PEX_PWR_EN")
		)
		(pad "2" smd circle
			(at 0.40005 0)
			(size 0 0)
			(layers "F.Cu" "F.Mask" "F.Paste")
			(net "NIC2_PEX_PWR_EN_R")
		)
	)
	(footprint ""
		(layer "F.Cu")
		(at 351.89668 -271.703546 -90)
		(property "Reference" "PC177"
			(at 0 0 270)
			(layer "F.SilkS")
			(hide yes)
			(effects
				(font
					(size 1.27 1.27)
				)
			)
		)
		(property "Value" ""
			(at 0 0 270)
			(layer "F.Fab")
			(effects
				(font
					(size 1.27 1.27)
				)
			)
		)
		(duplicate_pad_numbers_are_jumpers no)
		(fp_line
			(start -2.146046 3.400044)
			(end -3.400044 2.146046)
			(stroke
				(width 0.1524)
				(type default)
			)
			(layer "F.SilkS")
		)
		(fp_line
			(start 3.400044 3.400044)
			(end -2.146046 3.400044)
			(stroke
				(width 0.1524)
				(type default)
			)
			(layer "F.SilkS")
		)
		(fp_line
			(start -3.400044 2.146046)
			(end -3.400044 0.9398)
			(stroke
				(width 0.1524)
				(type default)
			)
			(layer "F.SilkS")
		)
		(fp_line
			(start 3.400044 0.9398)
			(end 3.400044 3.400044)
			(stroke
				(width 0.1524)
				(type default)
			)
			(layer "F.SilkS")
		)
		(fp_line
			(start 3.400044 -0.9398)
			(end 3.400044 -3.400044)
			(stroke
				(width 0.1524)
				(type default)
			)
			(layer "F.SilkS")
		)
		(fp_line
			(start -3.400044 -2.146046)
			(end -3.400044 -0.9398)
			(stroke
				(width 0.1524)
				(type default)
			)
			(layer "F.SilkS")
		)
		(fp_line
			(start -2.146046 -3.400044)
			(end -3.400044 -2.146046)
			(stroke
				(width 0.1524)
				(type default)
			)
			(layer "F.SilkS")
		)
		(fp_line
			(start 3.400044 -3.400044)
			(end -2.146046 -3.400044)
			(stroke
				(width 0.1524)
				(type default)
			)
			(layer "F.SilkS")
		)
		(fp_line
			(start -3.400044 3.400044)
			(end 3.400044 3.400044)
			(stroke
				(width 0.1)
				(type default)
			)
			(layer "F.Fab")
		)
		(fp_line
			(start 3.400044 3.400044)
			(end 3.400044 -3.400044)
			(stroke
				(width 0.1)
				(type default)
			)
			(layer "F.Fab")
		)
		(fp_line
			(start -3.400044 -3.400044)
			(end -3.400044 3.400044)
			(stroke
				(width 0.1)
				(type default)
			)
			(layer "F.Fab")
		)
		(fp_line
			(start 3.400044 -3.400044)
			(end -3.400044 -3.400044)
			(stroke
				(width 0.1)
				(type default)
			)
			(layer "F.Fab")
		)
		(pad "1" smd rect
			(at -2.70002 0 180)
			(size 1.6002 3.5052)
			(layers "F.Cu" "F.Mask" "F.Paste")
			(net "SW_P12V_P0V8_PEX3_FLT")
		)
		(pad "2" smd rect
			(at 2.70002 0 180)
			(size 1.6002 3.5052)
			(layers "F.Cu" "F.Mask" "F.Paste")
			(net "GND")
		)
	)
	(footprint ""
		(layer "F.Cu")
		(at 166.330884 -198.916798)
		(property "Reference" "R3402"
			(at 0 0 0)
			(layer "F.SilkS")
			(hide yes)
			(effects
				(font
					(size 1.27 1.27)
				)
			)
		)
		(property "Value" ""
			(at 0 0 0)
			(layer "F.Fab")
			(effects
				(font
					(size 1.27 1.27)
				)
			)
		)
		(duplicate_pad_numbers_are_jumpers no)
		(fp_line
			(start -0.7874 -0.4064)
			(end 0.7874 -0.4064)
			(stroke
				(width 0.1524)
				(type default)
			)
			(layer "F.SilkS")
		)
		(fp_line
			(start -0.7874 0.4064)
			(end -0.7874 -0.4064)
			(stroke
				(width 0.1524)
				(type default)
			)
			(layer "F.SilkS")
		)
		(fp_line
			(start 0.7874 -0.4064)
			(end 0.7874 0.4064)
			(stroke
				(width 0.1524)
				(type default)
			)
			(layer "F.SilkS")
		)
		(fp_line
			(start 0.7874 0.4064)
			(end -0.7874 0.4064)
			(stroke
				(width 0.1524)
				(type default)
			)
			(layer "F.SilkS")
		)
		(fp_line
			(start -0.67945 -0.305054)
			(end -0.12065 -0.305054)
			(stroke
				(width 0.1)
				(type default)
			)
			(layer "F.Fab")
		)
		(fp_line
			(start -0.67945 0.3048)
			(end -0.67945 -0.305054)
			(stroke
				(width 0.1)
				(type default)
			)
			(layer "F.Fab")
		)
		(fp_line
			(start -0.12065 -0.305054)
			(end -0.12065 -0.2794)
			(stroke
				(width 0.1)
				(type default)
			)
			(layer "F.Fab")
		)
		(fp_line
			(start -0.12065 -0.2794)
			(end 0.12065 -0.2794)
			(stroke
				(width 0.1)
				(type default)
			)
			(layer "F.Fab")
		)
		(fp_line
			(start -0.12065 0.2794)
			(end -0.12065 0.3048)
			(stroke
				(width 0.1)
				(type default)
			)
			(layer "F.Fab")
		)
		(fp_line
			(start -0.12065 0.3048)
			(end -0.67945 0.3048)
			(stroke
				(width 0.1)
				(type default)
			)
			(layer "F.Fab")
		)
		(fp_line
			(start 0.120396 0.2794)
			(end -0.12065 0.2794)
			(stroke
				(width 0.1)
				(type default)
			)
			(layer "F.Fab")
		)
		(fp_line
			(start 0.120396 0.3048)
			(end 0.120396 0.2794)
			(stroke
				(width 0.1)
				(type default)
			)
			(layer "F.Fab")
		)
		(fp_line
			(start 0.12065 -0.3048)
			(end 0.67945 -0.3048)
			(stroke
				(width 0.1)
				(type default)
			)
			(layer "F.Fab")
		)
		(fp_line
			(start 0.12065 -0.2794)
			(end 0.12065 -0.3048)
			(stroke
				(width 0.1)
				(type default)
			)
			(layer "F.Fab")
		)
		(fp_line
			(start 0.67945 -0.3048)
			(end 0.67945 0.3048)
			(stroke
				(width 0.1)
				(type default)
			)
			(layer "F.Fab")
		)
		(fp_line
			(start 0.67945 0.3048)
			(end 0.120396 0.3048)
			(stroke
				(width 0.1)
				(type default)
			)
			(layer "F.Fab")
		)
		(pad "1" smd circle
			(at -0.40005 0)
			(size 0 0)
			(layers "F.Cu" "F.Mask" "F.Paste")
			(net "SPI_BIC1_CS0_LS01_R1_N")
		)
		(pad "2" smd circle
			(at 0.40005 0)
			(size 0 0)
			(layers "F.Cu" "F.Mask" "F.Paste")
			(net "SPI_BIC1_CS0_LS01_R_N")
		)
	)
	(footprint ""
		(layer "F.Cu")
		(at 15.63497 -247.598184 -90)
		(property "Reference" "C4231"
			(at 0 0 270)
			(layer "F.SilkS")
			(hide yes)
			(effects
				(font
					(size 1.27 1.27)
				)
			)
		)
		(property "Value" ""
			(at 0 0 270)
			(layer "F.Fab")
			(effects
				(font
					(size 1.27 1.27)
				)
			)
		)
		(duplicate_pad_numbers_are_jumpers no)
		(fp_line
			(start -1.524 0.762)
			(end -1.524 -0.762)
			(stroke
				(width 0.1524)
				(type default)
			)
			(layer "F.SilkS")
		)
		(fp_line
			(start 1.524 0.762)
			(end -1.524 0.762)
			(stroke
				(width 0.1524)
				(type default)
			)
			(layer "F.SilkS")
		)
		(fp_line
			(start -1.524 -0.762)
			(end 1.524 -0.762)
			(stroke
				(width 0.1524)
				(type default)
			)
			(layer "F.SilkS")
		)
		(fp_line
			(start 1.524 -0.762)
			(end 1.524 0.762)
			(stroke
				(width 0.1524)
				(type default)
			)
			(layer "F.SilkS")
		)
		(fp_line
			(start -1.1049 0.724916)
			(end 1.1049 0.724916)
			(stroke
				(width 0.1)
				(type default)
			)
			(layer "F.Fab")
		)
		(fp_line
			(start 1.1049 0.724916)
			(end 1.1049 -0.724916)
			(stroke
				(width 0.1)
				(type default)
			)
			(layer "F.Fab")
		)
		(fp_line
			(start -1.1049 -0.724916)
			(end -1.1049 0.724916)
			(stroke
				(width 0.1)
				(type default)
			)
			(layer "F.Fab")
		)
		(fp_line
			(start 1.1049 -0.724916)
			(end -1.1049 -0.724916)
			(stroke
				(width 0.1)
				(type default)
			)
			(layer "F.Fab")
		)
		(pad "1" smd rect
			(at -0.889 0 90)
			(size 1.016 1.27)
			(layers "F.Cu" "F.Mask" "F.Paste")
			(net "P1V25_SERDES_VDDPLL_PEX0_C5")
		)
		(pad "2" smd rect
			(at 0.889 0 90)
			(size 1.016 1.27)
			(layers "F.Cu" "F.Mask" "F.Paste")
			(net "GND")
		)
		(zone
			(layer "F.Cu")
			(hatch none 0.5)
			(connect_pads
				(clearance 0)
			)
			(min_thickness 0.25)
			(keepout
				(tracks not_allowed)
				(vias allowed)
				(pads allowed)
				(copperpour not_allowed)
				(footprints allowed)
			)
			(placement
				(enabled no)
				(sheetname "")
			)
			(fill
				(thermal_gap 0.5)
				(thermal_bridge_width 0.5)
				(island_removal_mode 0)
			)
			(polygon
				(pts
					(xy 16.359886 -247.928384) (xy 14.910054 -247.928384) (xy 14.910054 -247.267984) (xy 16.359886 -247.267984)
				)
			)
		)
	)
	(footprint ""
		(layer "F.Cu")
		(at 237.900464 -227.737416 90)
		(property "Reference" "C4436"
			(at 0 0 90)
			(layer "F.SilkS")
			(hide yes)
			(effects
				(font
					(size 1.27 1.27)
				)
			)
		)
		(property "Value" ""
			(at 0 0 90)
			(layer "F.Fab")
			(effects
				(font
					(size 1.27 1.27)
				)
			)
		)
		(duplicate_pad_numbers_are_jumpers no)
		(fp_line
			(start 0.7874 -0.4064)
			(end 0.7874 0.4064)
			(stroke
				(width 0.1524)
				(type default)
			)
			(layer "F.SilkS")
		)
		(fp_line
			(start -0.7874 -0.4064)
			(end 0.7874 -0.4064)
			(stroke
				(width 0.1524)
				(type default)
			)
			(layer "F.SilkS")
		)
		(fp_line
			(start 0.7874 0.4064)
			(end -0.7874 0.4064)
			(stroke
				(width 0.1524)
				(type default)
			)
			(layer "F.SilkS")
		)
		(fp_line
			(start -0.7874 0.4064)
			(end -0.7874 -0.4064)
			(stroke
				(width 0.1524)
				(type default)
			)
			(layer "F.SilkS")
		)
		(fp_line
			(start -0.12065 -0.305054)
			(end -0.12065 -0.2794)
			(stroke
				(width 0.1)
				(type default)
			)
			(layer "F.Fab")
		)
		(fp_line
			(start -0.67945 -0.305054)
			(end -0.12065 -0.305054)
			(stroke
				(width 0.1)
				(type default)
			)
			(layer "F.Fab")
		)
		(fp_line
			(start 0.67945 -0.3048)
			(end 0.67945 0.3048)
			(stroke
				(width 0.1)
				(type default)
			)
			(layer "F.Fab")
		)
		(fp_line
			(start 0.12065 -0.3048)
			(end 0.67945 -0.3048)
			(stroke
				(width 0.1)
				(type default)
			)
			(layer "F.Fab")
		)
		(fp_line
			(start 0.12065 -0.2794)
			(end 0.12065 -0.3048)
			(stroke
				(width 0.1)
				(type default)
			)
			(layer "F.Fab")
		)
		(fp_line
			(start -0.12065 -0.2794)
			(end 0.12065 -0.2794)
			(stroke
				(width 0.1)
				(type default)
			)
			(layer "F.Fab")
		)
		(fp_line
			(start 0.120396 0.2794)
			(end -0.12065 0.2794)
			(stroke
				(width 0.1)
				(type default)
			)
			(layer "F.Fab")
		)
		(fp_line
			(start -0.12065 0.2794)
			(end -0.12065 0.3048)
			(stroke
				(width 0.1)
				(type default)
			)
			(layer "F.Fab")
		)
		(fp_line
			(start 0.67945 0.3048)
			(end 0.120396 0.3048)
			(stroke
				(width 0.1)
				(type default)
			)
			(layer "F.Fab")
		)
		(fp_line
			(start 0.120396 0.3048)
			(end 0.120396 0.2794)
			(stroke
				(width 0.1)
				(type default)
			)
			(layer "F.Fab")
		)
		(fp_line
			(start -0.12065 0.3048)
			(end -0.67945 0.3048)
			(stroke
				(width 0.1)
				(type default)
			)
			(layer "F.Fab")
		)
		(fp_line
			(start -0.67945 0.3048)
			(end -0.67945 -0.305054)
			(stroke
				(width 0.1)
				(type default)
			)
			(layer "F.Fab")
		)
		(pad "1" smd circle
			(at -0.40005 0 90)
			(size 0 0)
			(layers "F.Cu" "F.Mask" "F.Paste")
			(net "P1V8_PLL0_PEX2_SCALED")
		)
		(pad "2" smd circle
			(at 0.40005 0 90)
			(size 0 0)
			(layers "F.Cu" "F.Mask" "F.Paste")
			(net "GND")
		)
	)
	(footprint ""
		(layer "F.Cu")
		(at 204.85227 -375.060464 180)
		(property "Reference" "PR3"
			(at 0 0 180)
			(layer "F.SilkS")
			(hide yes)
			(effects
				(font
					(size 1.27 1.27)
				)
			)
		)
		(property "Value" ""
			(at 0 0 180)
			(layer "F.Fab")
			(effects
				(font
					(size 1.27 1.27)
				)
			)
		)
		(duplicate_pad_numbers_are_jumpers no)
		(fp_line
			(start 0.7874 0.4064)
			(end -0.7874 0.4064)
			(stroke
				(width 0.1524)
				(type default)
			)
			(layer "F.SilkS")
		)
		(fp_line
			(start 0.7874 -0.4064)
			(end 0.7874 0.4064)
			(stroke
				(width 0.1524)
				(type default)
			)
			(layer "F.SilkS")
		)
		(fp_line
			(start -0.7874 0.4064)
			(end -0.7874 -0.4064)
			(stroke
				(width 0.1524)
				(type default)
			)
			(layer "F.SilkS")
		)
		(fp_line
			(start -0.7874 -0.4064)
			(end 0.7874 -0.4064)
			(stroke
				(width 0.1524)
				(type default)
			)
			(layer "F.SilkS")
		)
		(fp_line
			(start 0.67945 0.3048)
			(end 0.120396 0.3048)
			(stroke
				(width 0.1)
				(type default)
			)
			(layer "F.Fab")
		)
		(fp_line
			(start 0.67945 -0.3048)
			(end 0.67945 0.3048)
			(stroke
				(width 0.1)
				(type default)
			)
			(layer "F.Fab")
		)
		(fp_line
			(start 0.12065 -0.2794)
			(end 0.12065 -0.3048)
			(stroke
				(width 0.1)
				(type default)
			)
			(layer "F.Fab")
		)
		(fp_line
			(start 0.12065 -0.3048)
			(end 0.67945 -0.3048)
			(stroke
				(width 0.1)
				(type default)
			)
			(layer "F.Fab")
		)
		(fp_line
			(start 0.120396 0.3048)
			(end 0.120396 0.2794)
			(stroke
				(width 0.1)
				(type default)
			)
			(layer "F.Fab")
		)
		(fp_line
			(start 0.120396 0.2794)
			(end -0.12065 0.2794)
			(stroke
				(width 0.1)
				(type default)
			)
			(layer "F.Fab")
		)
		(fp_line
			(start -0.12065 0.3048)
			(end -0.67945 0.3048)
			(stroke
				(width 0.1)
				(type default)
			)
			(layer "F.Fab")
		)
		(fp_line
			(start -0.12065 0.2794)
			(end -0.12065 0.3048)
			(stroke
				(width 0.1)
				(type default)
			)
			(layer "F.Fab")
		)
		(fp_line
			(start -0.12065 -0.2794)
			(end 0.12065 -0.2794)
			(stroke
				(width 0.1)
				(type default)
			)
			(layer "F.Fab")
		)
		(fp_line
			(start -0.12065 -0.305054)
			(end -0.12065 -0.2794)
			(stroke
				(width 0.1)
				(type default)
			)
			(layer "F.Fab")
		)
		(fp_line
			(start -0.67945 0.3048)
			(end -0.67945 -0.305054)
			(stroke
				(width 0.1)
				(type default)
			)
			(layer "F.Fab")
		)
		(fp_line
			(start -0.67945 -0.305054)
			(end -0.12065 -0.305054)
			(stroke
				(width 0.1)
				(type default)
			)
			(layer "F.Fab")
		)
		(pad "1" smd circle
			(at -0.40005 0 180)
			(size 0 0)
			(layers "F.Cu" "F.Mask" "F.Paste")
			(net "P12V_STBY")
		)
		(pad "2" smd circle
			(at 0.40005 0 180)
			(size 0 0)
			(layers "F.Cu" "F.Mask" "F.Paste")
			(net "HSC_VINSEN")
		)
	)
)
